(kicad_pcb
	(version 20260206)
	(generator "pcbnew")
	(generator_version "10.0")
	(general
		(thickness 1.6)
		(legacy_teardrops no)
	)
	(paper "A4")
	(title_block
		(title "9054_F0T_PDB_BD_GPU_F_V04_1213_1550_OCP.brd")
		(comment 1 "Grand Teton / footprints 521-526 of 608")
	)
	(layers
		(0 "F.Cu" signal "TOP")
		(4 "In1.Cu" signal "GND")
		(6 "In2.Cu" signal "IN1")
		(8 "In3.Cu" signal "GND1")
		(10 "In4.Cu" signal "VCC")
		(12 "In5.Cu" signal "VCC1")
		(14 "In6.Cu" signal "GND2")
		(16 "In7.Cu" signal "IN2")
		(18 "In8.Cu" signal "GND3")
		(2 "B.Cu" signal "BOTTOM")
		(9 "F.Adhes" user "F.Adhesive")
		(11 "B.Adhes" user "B.Adhesive")
		(13 "F.Paste" user "Package Geometry/Pastemask Top")
		(15 "B.Paste" user "Package Geometry/Pastemask Bottom")
		(5 "F.SilkS" user "Ref Des/Silkscreen Top")
		(7 "B.SilkS" user "Ref Des/Silkscreen Bottom")
		(1 "F.Mask" user "Board Geometry/Soldermask Top")
		(3 "B.Mask" user "Board Geometry/Soldermask Bottom")
		(17 "Dwgs.User" user "User.Drawings")
		(19 "Cmts.User" user "User.Comments")
		(21 "Eco1.User" user "User.Eco1")
		(23 "Eco2.User" user "User.Eco2")
		(25 "Edge.Cuts" user "Board Geometry/Outline")
		(27 "Margin" user)
		(31 "F.CrtYd" user "Package Geometry/Place Bound Top")
		(29 "B.CrtYd" user "Package Geometry/Place Bound Bottom")
		(35 "F.Fab" user "Ref Des/Assembly Top")
		(33 "B.Fab" user "Ref Des/Assembly Bottom")
	)
	(footprint ""
		(layer "B.Cu")
		(at 169.1894 -78.359 180)
		(property "Reference" "R5889"
			(at 0 0 0)
			(layer "B.SilkS")
			(hide yes)
			(effects
				(font
					(size 1.27 1.27)
				)
				(justify mirror)
			)
		)
		(property "Value" ""
			(at 0 0 0)
			(layer "B.Fab")
			(effects
				(font
					(size 1.27 1.27)
				)
				(justify mirror)
			)
		)
		(duplicate_pad_numbers_are_jumpers no)
		(fp_line
			(start 0.7874 0.4064)
			(end 0.7874 -0.4064)
			(stroke
				(width 0.1524)
				(type default)
			)
			(layer "B.SilkS")
		)
		(fp_line
			(start 0.7874 -0.4064)
			(end -0.7874 -0.4064)
			(stroke
				(width 0.1524)
				(type default)
			)
			(layer "B.SilkS")
		)
		(fp_line
			(start -0.7874 0.4064)
			(end 0.7874 0.4064)
			(stroke
				(width 0.1524)
				(type default)
			)
			(layer "B.SilkS")
		)
		(fp_line
			(start -0.7874 -0.4064)
			(end -0.7874 0.4064)
			(stroke
				(width 0.1524)
				(type default)
			)
			(layer "B.SilkS")
		)
		(fp_line
			(start 0.67945 0.3048)
			(end 0.67945 -0.305054)
			(stroke
				(width 0.1)
				(type default)
			)
			(layer "B.Fab")
		)
		(fp_line
			(start 0.67945 -0.305054)
			(end 0.12065 -0.305054)
			(stroke
				(width 0.1)
				(type default)
			)
			(layer "B.Fab")
		)
		(fp_line
			(start 0.12065 0.3048)
			(end 0.67945 0.3048)
			(stroke
				(width 0.1)
				(type default)
			)
			(layer "B.Fab")
		)
		(fp_line
			(start 0.12065 0.2794)
			(end 0.12065 0.3048)
			(stroke
				(width 0.1)
				(type default)
			)
			(layer "B.Fab")
		)
		(fp_line
			(start 0.12065 -0.2794)
			(end -0.12065 -0.2794)
			(stroke
				(width 0.1)
				(type default)
			)
			(layer "B.Fab")
		)
		(fp_line
			(start 0.12065 -0.305054)
			(end 0.12065 -0.2794)
			(stroke
				(width 0.1)
				(type default)
			)
			(layer "B.Fab")
		)
		(fp_line
			(start -0.120396 0.3048)
			(end -0.120396 0.2794)
			(stroke
				(width 0.1)
				(type default)
			)
			(layer "B.Fab")
		)
		(fp_line
			(start -0.120396 0.2794)
			(end 0.12065 0.2794)
			(stroke
				(width 0.1)
				(type default)
			)
			(layer "B.Fab")
		)
		(fp_line
			(start -0.12065 -0.2794)
			(end -0.12065 -0.3048)
			(stroke
				(width 0.1)
				(type default)
			)
			(layer "B.Fab")
		)
		(fp_line
			(start -0.12065 -0.3048)
			(end -0.67945 -0.3048)
			(stroke
				(width 0.1)
				(type default)
			)
			(layer "B.Fab")
		)
		(fp_line
			(start -0.67945 0.3048)
			(end -0.120396 0.3048)
			(stroke
				(width 0.1)
				(type default)
			)
			(layer "B.Fab")
		)
		(fp_line
			(start -0.67945 -0.3048)
			(end -0.67945 0.3048)
			(stroke
				(width 0.1)
				(type default)
			)
			(layer "B.Fab")
		)
		(pad "1" smd circle
			(at 0.40005 0)
			(size 0 0)
			(layers "B.Cu" "B.Mask" "B.Paste")
			(net "P3V3_AUX")
		)
		(pad "2" smd circle
			(at -0.40005 0)
			(size 0 0)
			(layers "B.Cu" "B.Mask" "B.Paste")
			(net "P52V_HS2_GPO1")
		)
	)
	(footprint ""
		(layer "B.Cu")
		(at 173.147736 -56.007 -90)
		(property "Reference" "PR7019"
			(at 0 0 90)
			(layer "B.SilkS")
			(hide yes)
			(effects
				(font
					(size 1.27 1.27)
				)
				(justify mirror)
			)
		)
		(property "Value" ""
			(at 0 0 90)
			(layer "B.Fab")
			(effects
				(font
					(size 1.27 1.27)
				)
				(justify mirror)
			)
		)
		(duplicate_pad_numbers_are_jumpers no)
		(fp_line
			(start -1.651 0.8382)
			(end 1.651 0.8382)
			(stroke
				(width 0.1524)
				(type default)
			)
			(layer "B.SilkS")
		)
		(fp_line
			(start 1.651 0.8382)
			(end 1.651 -0.8382)
			(stroke
				(width 0.1524)
				(type default)
			)
			(layer "B.SilkS")
		)
		(fp_line
			(start -1.651 -0.8382)
			(end -1.651 0.8382)
			(stroke
				(width 0.1524)
				(type default)
			)
			(layer "B.SilkS")
		)
		(fp_line
			(start 1.651 -0.8382)
			(end -1.651 -0.8382)
			(stroke
				(width 0.1524)
				(type default)
			)
			(layer "B.SilkS")
		)
		(fp_line
			(start -1.560576 0.7366)
			(end -1.560576 -0.7366)
			(stroke
				(width 0.1)
				(type default)
			)
			(layer "B.Fab")
		)
		(fp_line
			(start -1.524 0.7366)
			(end -1.560576 0.7366)
			(stroke
				(width 0.1)
				(type default)
			)
			(layer "B.Fab")
		)
		(fp_line
			(start 1.524 0.7366)
			(end -1.524 0.7366)
			(stroke
				(width 0.1)
				(type default)
			)
			(layer "B.Fab")
		)
		(fp_line
			(start 1.559814 0.7366)
			(end 1.524 0.7366)
			(stroke
				(width 0.1)
				(type default)
			)
			(layer "B.Fab")
		)
		(fp_line
			(start -1.560576 -0.7366)
			(end -1.524 -0.7366)
			(stroke
				(width 0.1)
				(type default)
			)
			(layer "B.Fab")
		)
		(fp_line
			(start -1.524 -0.7366)
			(end 1.524 -0.7366)
			(stroke
				(width 0.1)
				(type default)
			)
			(layer "B.Fab")
		)
		(fp_line
			(start 1.524 -0.7366)
			(end 1.559814 -0.7366)
			(stroke
				(width 0.1)
				(type default)
			)
			(layer "B.Fab")
		)
		(fp_line
			(start 1.559814 -0.7366)
			(end 1.559814 0.7366)
			(stroke
				(width 0.1)
				(type default)
			)
			(layer "B.Fab")
		)
		(pad "1" smd rect
			(at 0.94996 0 270)
			(size 1.1176 1.3716)
			(layers "B.Cu" "B.Mask" "B.Paste")
			(net "P52V_2")
		)
		(pad "2" smd rect
			(at -0.94996 0 270)
			(size 1.1176 1.3716)
			(layers "B.Cu" "B.Mask" "B.Paste")
			(net "P52V_HS2_UVH")
		)
	)
	(footprint ""
		(layer "B.Cu")
		(at 293.6494 -77.851)
		(property "Reference" "PR24"
			(at 0 0 0)
			(layer "B.SilkS")
			(hide yes)
			(effects
				(font
					(size 1.27 1.27)
				)
				(justify mirror)
			)
		)
		(property "Value" ""
			(at 0 0 0)
			(layer "B.Fab")
			(effects
				(font
					(size 1.27 1.27)
				)
				(justify mirror)
			)
		)
		(duplicate_pad_numbers_are_jumpers no)
		(fp_line
			(start -0.7874 -0.4064)
			(end -0.7874 0.4064)
			(stroke
				(width 0.1524)
				(type default)
			)
			(layer "B.SilkS")
		)
		(fp_line
			(start -0.7874 0.4064)
			(end 0.7874 0.4064)
			(stroke
				(width 0.1524)
				(type default)
			)
			(layer "B.SilkS")
		)
		(fp_line
			(start 0.7874 -0.4064)
			(end -0.7874 -0.4064)
			(stroke
				(width 0.1524)
				(type default)
			)
			(layer "B.SilkS")
		)
		(fp_line
			(start 0.7874 0.4064)
			(end 0.7874 -0.4064)
			(stroke
				(width 0.1524)
				(type default)
			)
			(layer "B.SilkS")
		)
		(fp_line
			(start -0.67945 -0.3048)
			(end -0.67945 0.3048)
			(stroke
				(width 0.1)
				(type default)
			)
			(layer "B.Fab")
		)
		(fp_line
			(start -0.67945 0.3048)
			(end -0.120396 0.3048)
			(stroke
				(width 0.1)
				(type default)
			)
			(layer "B.Fab")
		)
		(fp_line
			(start -0.12065 -0.3048)
			(end -0.67945 -0.3048)
			(stroke
				(width 0.1)
				(type default)
			)
			(layer "B.Fab")
		)
		(fp_line
			(start -0.12065 -0.2794)
			(end -0.12065 -0.3048)
			(stroke
				(width 0.1)
				(type default)
			)
			(layer "B.Fab")
		)
		(fp_line
			(start -0.120396 0.2794)
			(end 0.12065 0.2794)
			(stroke
				(width 0.1)
				(type default)
			)
			(layer "B.Fab")
		)
		(fp_line
			(start -0.120396 0.3048)
			(end -0.120396 0.2794)
			(stroke
				(width 0.1)
				(type default)
			)
			(layer "B.Fab")
		)
		(fp_line
			(start 0.12065 -0.305054)
			(end 0.12065 -0.2794)
			(stroke
				(width 0.1)
				(type default)
			)
			(layer "B.Fab")
		)
		(fp_line
			(start 0.12065 -0.2794)
			(end -0.12065 -0.2794)
			(stroke
				(width 0.1)
				(type default)
			)
			(layer "B.Fab")
		)
		(fp_line
			(start 0.12065 0.2794)
			(end 0.12065 0.3048)
			(stroke
				(width 0.1)
				(type default)
			)
			(layer "B.Fab")
		)
		(fp_line
			(start 0.12065 0.3048)
			(end 0.67945 0.3048)
			(stroke
				(width 0.1)
				(type default)
			)
			(layer "B.Fab")
		)
		(fp_line
			(start 0.67945 -0.305054)
			(end 0.12065 -0.305054)
			(stroke
				(width 0.1)
				(type default)
			)
			(layer "B.Fab")
		)
		(fp_line
			(start 0.67945 0.3048)
			(end 0.67945 -0.305054)
			(stroke
				(width 0.1)
				(type default)
			)
			(layer "B.Fab")
		)
		(pad "1" smd circle
			(at 0.40005 0 180)
			(size 0 0)
			(layers "B.Cu" "B.Mask" "B.Paste")
			(net "P52V_HS1_FB")
		)
		(pad "2" smd circle
			(at -0.40005 0 180)
			(size 0 0)
			(layers "B.Cu" "B.Mask" "B.Paste")
			(net "GND_FIELD_SIGNAL")
		)
	)
	(footprint ""
		(layer "B.Cu")
		(at 291.9984 -62.992 -90)
		(property "Reference" "R156"
			(at 0 0 90)
			(layer "B.SilkS")
			(hide yes)
			(effects
				(font
					(size 1.27 1.27)
				)
				(justify mirror)
			)
		)
		(property "Value" ""
			(at 0 0 90)
			(layer "B.Fab")
			(effects
				(font
					(size 1.27 1.27)
				)
				(justify mirror)
			)
		)
		(duplicate_pad_numbers_are_jumpers no)
		(fp_line
			(start -0.7874 0.4064)
			(end 0.7874 0.4064)
			(stroke
				(width 0.1524)
				(type default)
			)
			(layer "B.SilkS")
		)
		(fp_line
			(start 0.7874 0.4064)
			(end 0.7874 -0.4064)
			(stroke
				(width 0.1524)
				(type default)
			)
			(layer "B.SilkS")
		)
		(fp_line
			(start -0.7874 -0.4064)
			(end -0.7874 0.4064)
			(stroke
				(width 0.1524)
				(type default)
			)
			(layer "B.SilkS")
		)
		(fp_line
			(start 0.7874 -0.4064)
			(end -0.7874 -0.4064)
			(stroke
				(width 0.1524)
				(type default)
			)
			(layer "B.SilkS")
		)
		(fp_line
			(start -0.67945 0.3048)
			(end -0.120396 0.3048)
			(stroke
				(width 0.1)
				(type default)
			)
			(layer "B.Fab")
		)
		(fp_line
			(start -0.120396 0.3048)
			(end -0.120396 0.2794)
			(stroke
				(width 0.1)
				(type default)
			)
			(layer "B.Fab")
		)
		(fp_line
			(start 0.12065 0.3048)
			(end 0.67945 0.3048)
			(stroke
				(width 0.1)
				(type default)
			)
			(layer "B.Fab")
		)
		(fp_line
			(start 0.67945 0.3048)
			(end 0.67945 -0.305054)
			(stroke
				(width 0.1)
				(type default)
			)
			(layer "B.Fab")
		)
		(fp_line
			(start -0.120396 0.2794)
			(end 0.12065 0.2794)
			(stroke
				(width 0.1)
				(type default)
			)
			(layer "B.Fab")
		)
		(fp_line
			(start 0.12065 0.2794)
			(end 0.12065 0.3048)
			(stroke
				(width 0.1)
				(type default)
			)
			(layer "B.Fab")
		)
		(fp_line
			(start -0.12065 -0.2794)
			(end -0.12065 -0.3048)
			(stroke
				(width 0.1)
				(type default)
			)
			(layer "B.Fab")
		)
		(fp_line
			(start 0.12065 -0.2794)
			(end -0.12065 -0.2794)
			(stroke
				(width 0.1)
				(type default)
			)
			(layer "B.Fab")
		)
		(fp_line
			(start -0.67945 -0.3048)
			(end -0.67945 0.3048)
			(stroke
				(width 0.1)
				(type default)
			)
			(layer "B.Fab")
		)
		(fp_line
			(start -0.12065 -0.3048)
			(end -0.67945 -0.3048)
			(stroke
				(width 0.1)
				(type default)
			)
			(layer "B.Fab")
		)
		(fp_line
			(start 0.12065 -0.305054)
			(end 0.12065 -0.2794)
			(stroke
				(width 0.1)
				(type default)
			)
			(layer "B.Fab")
		)
		(fp_line
			(start 0.67945 -0.305054)
			(end 0.12065 -0.305054)
			(stroke
				(width 0.1)
				(type default)
			)
			(layer "B.Fab")
		)
		(pad "1" smd circle
			(at 0.40005 0 90)
			(size 0 0)
			(layers "B.Cu" "B.Mask" "B.Paste")
			(net "P52V_HS1_INTVCC")
		)
		(pad "2" smd circle
			(at -0.40005 0 90)
			(size 0 0)
			(layers "B.Cu" "B.Mask" "B.Paste")
			(net "P52V_HS1_ADR0")
		)
	)
	(footprint ""
		(layer "B.Cu")
		(at 260.6294 -52.959 180)
		(property "Reference" "R399"
			(at 0 0 0)
			(layer "B.SilkS")
			(hide yes)
			(effects
				(font
					(size 1.27 1.27)
				)
				(justify mirror)
			)
		)
		(property "Value" ""
			(at 0 0 0)
			(layer "B.Fab")
			(effects
				(font
					(size 1.27 1.27)
				)
				(justify mirror)
			)
		)
		(duplicate_pad_numbers_are_jumpers no)
		(fp_line
			(start 0.7874 0.4064)
			(end 0.7874 -0.4064)
			(stroke
				(width 0.1524)
				(type default)
			)
			(layer "B.SilkS")
		)
		(fp_line
			(start 0.7874 -0.4064)
			(end -0.7874 -0.4064)
			(stroke
				(width 0.1524)
				(type default)
			)
			(layer "B.SilkS")
		)
		(fp_line
			(start -0.7874 0.4064)
			(end 0.7874 0.4064)
			(stroke
				(width 0.1524)
				(type default)
			)
			(layer "B.SilkS")
		)
		(fp_line
			(start -0.7874 -0.4064)
			(end -0.7874 0.4064)
			(stroke
				(width 0.1524)
				(type default)
			)
			(layer "B.SilkS")
		)
		(fp_line
			(start 0.67945 0.3048)
			(end 0.67945 -0.305054)
			(stroke
				(width 0.1)
				(type default)
			)
			(layer "B.Fab")
		)
		(fp_line
			(start 0.67945 -0.305054)
			(end 0.12065 -0.305054)
			(stroke
				(width 0.1)
				(type default)
			)
			(layer "B.Fab")
		)
		(fp_line
			(start 0.12065 0.3048)
			(end 0.67945 0.3048)
			(stroke
				(width 0.1)
				(type default)
			)
			(layer "B.Fab")
		)
		(fp_line
			(start 0.12065 0.2794)
			(end 0.12065 0.3048)
			(stroke
				(width 0.1)
				(type default)
			)
			(layer "B.Fab")
		)
		(fp_line
			(start 0.12065 -0.2794)
			(end -0.12065 -0.2794)
			(stroke
				(width 0.1)
				(type default)
			)
			(layer "B.Fab")
		)
		(fp_line
			(start 0.12065 -0.305054)
			(end 0.12065 -0.2794)
			(stroke
				(width 0.1)
				(type default)
			)
			(layer "B.Fab")
		)
		(fp_line
			(start -0.120396 0.3048)
			(end -0.120396 0.2794)
			(stroke
				(width 0.1)
				(type default)
			)
			(layer "B.Fab")
		)
		(fp_line
			(start -0.120396 0.2794)
			(end 0.12065 0.2794)
			(stroke
				(width 0.1)
				(type default)
			)
			(layer "B.Fab")
		)
		(fp_line
			(start -0.12065 -0.2794)
			(end -0.12065 -0.3048)
			(stroke
				(width 0.1)
				(type default)
			)
			(layer "B.Fab")
		)
		(fp_line
			(start -0.12065 -0.3048)
			(end -0.67945 -0.3048)
			(stroke
				(width 0.1)
				(type default)
			)
			(layer "B.Fab")
		)
		(fp_line
			(start -0.67945 0.3048)
			(end -0.120396 0.3048)
			(stroke
				(width 0.1)
				(type default)
			)
			(layer "B.Fab")
		)
		(fp_line
			(start -0.67945 -0.3048)
			(end -0.67945 0.3048)
			(stroke
				(width 0.1)
				(type default)
			)
			(layer "B.Fab")
		)
		(pad "1" smd circle
			(at 0.40005 0)
			(size 0 0)
			(layers "B.Cu" "B.Mask" "B.Paste")
			(net "FM_HS1_EN_FUSE")
		)
		(pad "2" smd circle
			(at -0.40005 0)
			(size 0 0)
			(layers "B.Cu" "B.Mask" "B.Paste")
			(net "GND")
		)
	)
	(footprint ""
		(layer "B.Cu")
		(at 168.321736 -67.818)
		(property "Reference" "PR7028"
			(at 0 0 0)
			(layer "B.SilkS")
			(hide yes)
			(effects
				(font
					(size 1.27 1.27)
				)
				(justify mirror)
			)
		)
		(property "Value" ""
			(at 0 0 0)
			(layer "B.Fab")
			(effects
				(font
					(size 1.27 1.27)
				)
				(justify mirror)
			)
		)
		(duplicate_pad_numbers_are_jumpers no)
		(fp_line
			(start -0.7874 -0.4064)
			(end -0.7874 0.4064)
			(stroke
				(width 0.1524)
				(type default)
			)
			(layer "B.SilkS")
		)
		(fp_line
			(start -0.7874 0.4064)
			(end 0.7874 0.4064)
			(stroke
				(width 0.1524)
				(type default)
			)
			(layer "B.SilkS")
		)
		(fp_line
			(start 0.7874 -0.4064)
			(end -0.7874 -0.4064)
			(stroke
				(width 0.1524)
				(type default)
			)
			(layer "B.SilkS")
		)
		(fp_line
			(start 0.7874 0.4064)
			(end 0.7874 -0.4064)
			(stroke
				(width 0.1524)
				(type default)
			)
			(layer "B.SilkS")
		)
		(fp_line
			(start -0.67945 -0.3048)
			(end -0.67945 0.3048)
			(stroke
				(width 0.1)
				(type default)
			)
			(layer "B.Fab")
		)
		(fp_line
			(start -0.67945 0.3048)
			(end -0.120396 0.3048)
			(stroke
				(width 0.1)
				(type default)
			)
			(layer "B.Fab")
		)
		(fp_line
			(start -0.12065 -0.3048)
			(end -0.67945 -0.3048)
			(stroke
				(width 0.1)
				(type default)
			)
			(layer "B.Fab")
		)
		(fp_line
			(start -0.12065 -0.2794)
			(end -0.12065 -0.3048)
			(stroke
				(width 0.1)
				(type default)
			)
			(layer "B.Fab")
		)
		(fp_line
			(start -0.120396 0.2794)
			(end 0.12065 0.2794)
			(stroke
				(width 0.1)
				(type default)
			)
			(layer "B.Fab")
		)
		(fp_line
			(start -0.120396 0.3048)
			(end -0.120396 0.2794)
			(stroke
				(width 0.1)
				(type default)
			)
			(layer "B.Fab")
		)
		(fp_line
			(start 0.12065 -0.305054)
			(end 0.12065 -0.2794)
			(stroke
				(width 0.1)
				(type default)
			)
			(layer "B.Fab")
		)
		(fp_line
			(start 0.12065 -0.2794)
			(end -0.12065 -0.2794)
			(stroke
				(width 0.1)
				(type default)
			)
			(layer "B.Fab")
		)
		(fp_line
			(start 0.12065 0.2794)
			(end 0.12065 0.3048)
			(stroke
				(width 0.1)
				(type default)
			)
			(layer "B.Fab")
		)
		(fp_line
			(start 0.12065 0.3048)
			(end 0.67945 0.3048)
			(stroke
				(width 0.1)
				(type default)
			)
			(layer "B.Fab")
		)
		(fp_line
			(start 0.67945 -0.305054)
			(end 0.12065 -0.305054)
			(stroke
				(width 0.1)
				(type default)
			)
			(layer "B.Fab")
		)
		(fp_line
			(start 0.67945 0.3048)
			(end 0.67945 -0.305054)
			(stroke
				(width 0.1)
				(type default)
			)
			(layer "B.Fab")
		)
		(pad "1" smd circle
			(at 0.40005 0 180)
			(size 0 0)
			(layers "B.Cu" "B.Mask" "B.Paste")
			(net "P52V_HS2_ISTART")
		)
		(pad "2" smd circle
			(at -0.40005 0 180)
			(size 0 0)
			(layers "B.Cu" "B.Mask" "B.Paste")
			(net "GND1_FIELD_SIGNAL")
		)
	)
)
